(kicad_pcb
	(version 20241229)
	(generator "pcbnew")
	(generator_version "9.0")
	(general
		(thickness 1.62)
		(legacy_teardrops no)
	)
	(paper "A3")
	(title_block
		(title "COM Express 7 Baseboard")
		(date "2025-02-04")
		(rev "1.1.2")
		(company "Antmicro Ltd")
		(comment 1 "www.antmicro.com")
		(comment 9 "footprints 434-436 of 802")
	)
	(layers
		(0 "F.Cu" signal)
		(4 "In1.Cu" signal)
		(6 "In2.Cu" signal)
		(8 "In3.Cu" signal)
		(10 "In4.Cu" signal)
		(12 "In5.Cu" signal)
		(14 "In6.Cu" signal)
		(2 "B.Cu" signal)
		(9 "F.Adhes" user "F.Adhesive")
		(11 "B.Adhes" user "B.Adhesive")
		(13 "F.Paste" user)
		(15 "B.Paste" user)
		(5 "F.SilkS" user "F.Silkscreen")
		(7 "B.SilkS" user "B.Silkscreen")
		(1 "F.Mask" user)
		(3 "B.Mask" user)
		(17 "Dwgs.User" user "User.Drawings")
		(19 "Cmts.User" user "User.Comments")
		(21 "Eco1.User" user "User.Eco1")
		(23 "Eco2.User" user "User.Eco2")
		(25 "Edge.Cuts" user)
		(27 "Margin" user)
		(31 "F.CrtYd" user "F.Courtyard")
		(29 "B.CrtYd" user "B.Courtyard")
		(35 "F.Fab" user)
		(33 "B.Fab" user)
	)
	(footprint "antmicro-footprints:SOT-23-3"
		(layer "F.Cu")
		(at 258.125 131.51 90)
		(property "Reference" "Q12"
			(at 1.4 0.425 180)
			(layer "F.SilkS")
			(effects
				(font
					(size 0.7 0.7)
					(thickness 0.15)
				)
				(justify left bottom)
			)
		)
		(property "Value" "BSS138-7-F"
			(at -1.9 2.7 90)
			(layer "F.Fab")
			(effects
				(font
					(size 0.7 0.7)
					(thickness 0.15)
				)
				(justify left bottom)
			)
		)
		(property "Datasheet" "https://www.diodes.com/assets/Datasheets/ds30144.pdf"
			(at 0 0 90)
			(layer "F.Fab")
			(hide yes)
			(effects
				(font
					(size 1.27 1.27)
					(thickness 0.15)
				)
			)
		)
		(property "Author" "Antmicro"
			(at 389.635 -126.615 0)
			(layer "F.Fab")
			(hide yes)
			(effects
				(font
					(size 1 1)
					(thickness 0.15)
				)
			)
		)
		(property "License" "Apache-2.0"
			(at 389.635 -126.615 0)
			(layer "F.Fab")
			(hide yes)
			(effects
				(font
					(size 1 1)
					(thickness 0.15)
				)
			)
		)
		(property "MPN" "BSS138-7-F"
			(at 389.635 -126.615 0)
			(layer "F.Fab")
			(hide yes)
			(effects
				(font
					(size 1 1)
					(thickness 0.15)
				)
			)
		)
		(property "Manufacturer" "Diodes Incorporated"
			(at 389.635 -126.615 0)
			(layer "F.Fab")
			(hide yes)
			(effects
				(font
					(size 1 1)
					(thickness 0.15)
				)
			)
		)
		(sheetname "Com Express 7 MGMT")
		(sheetfile "com_express_7_mgmt.kicad_sch")
		(attr smd)
		(fp_line
			(start 0.7 -1.5)
			(end -0.7 -1.5)
			(stroke
				(width 0.15)
				(type solid)
			)
			(layer "F.SilkS")
		)
		(fp_line
			(start -0.85 -1.35)
			(end -0.7 -1.5)
			(stroke
				(width 0.15)
				(type solid)
			)
			(layer "F.SilkS")
		)
		(fp_line
			(start -1.45 -1.35)
			(end -0.85 -1.35)
			(stroke
				(width 0.15)
				(type solid)
			)
			(layer "F.SilkS")
		)
		(fp_line
			(start 0.7 -0.4)
			(end 0.7 -1.5)
			(stroke
				(width 0.15)
				(type solid)
			)
			(layer "F.SilkS")
		)
		(fp_line
			(start 0.7 0.4)
			(end 0.7 1.5)
			(stroke
				(width 0.15)
				(type solid)
			)
			(layer "F.SilkS")
		)
		(fp_line
			(start 0.7 1.5)
			(end -0.7 1.5)
			(stroke
				(width 0.15)
				(type solid)
			)
			(layer "F.SilkS")
		)
		(fp_line
			(start -0.7 1.5)
			(end -0.7 1.35)
			(stroke
				(width 0.15)
				(type solid)
			)
			(layer "F.SilkS")
		)
		(fp_line
			(start 0.825 -1.6)
			(end 0.825 -0.45)
			(stroke
				(width 0.05)
				(type solid)
			)
			(layer "F.CrtYd")
		)
		(fp_line
			(start -0.9 -1.6)
			(end 0.825 -1.6)
			(stroke
				(width 0.05)
				(type solid)
			)
			(layer "F.CrtYd")
		)
		(fp_line
			(start -0.9 -1.6)
			(end -0.9 -1.4)
			(stroke
				(width 0.05)
				(type solid)
			)
			(layer "F.CrtYd")
		)
		(fp_line
			(start -0.9 -1.4)
			(end -1.75 -1.4)
			(stroke
				(width 0.05)
				(type solid)
			)
			(layer "F.CrtYd")
		)
		(fp_line
			(start -0.85 -0.5)
			(end -1.75 -0.5)
			(stroke
				(width 0.05)
				(type solid)
			)
			(layer "F.CrtYd")
		)
		(fp_line
			(start -1.75 -0.5)
			(end -1.75 -1.4)
			(stroke
				(width 0.05)
				(type solid)
			)
			(layer "F.CrtYd")
		)
		(fp_line
			(start 1.75 -0.45)
			(end 1.75 0.45)
			(stroke
				(width 0.05)
				(type solid)
			)
			(layer "F.CrtYd")
		)
		(fp_line
			(start 0.825 -0.45)
			(end 1.75 -0.45)
			(stroke
				(width 0.05)
				(type solid)
			)
			(layer "F.CrtYd")
		)
		(fp_line
			(start 1.75 0.45)
			(end 0.85 0.45)
			(stroke
				(width 0.05)
				(type solid)
			)
			(layer "F.CrtYd")
		)
		(fp_line
			(start 0.85 0.45)
			(end 0.85 1.65)
			(stroke
				(width 0.05)
				(type solid)
			)
			(layer "F.CrtYd")
		)
		(fp_line
			(start -0.85 0.5)
			(end -0.85 -0.5)
			(stroke
				(width 0.05)
				(type solid)
			)
			(layer "F.CrtYd")
		)
		(fp_line
			(start -1.75 0.5)
			(end -0.85 0.5)
			(stroke
				(width 0.05)
				(type solid)
			)
			(layer "F.CrtYd")
		)
		(fp_line
			(start -0.85 1.4)
			(end -1.75 1.4)
			(stroke
				(width 0.05)
				(type solid)
			)
			(layer "F.CrtYd")
		)
		(fp_line
			(start -1.75 1.4)
			(end -1.75 0.5)
			(stroke
				(width 0.05)
				(type solid)
			)
			(layer "F.CrtYd")
		)
		(fp_line
			(start 0.85 1.65)
			(end -0.85 1.65)
			(stroke
				(width 0.05)
				(type solid)
			)
			(layer "F.CrtYd")
		)
		(fp_line
			(start -0.85 1.65)
			(end -0.85 1.4)
			(stroke
				(width 0.05)
				(type solid)
			)
			(layer "F.CrtYd")
		)
		(fp_line
			(start -0.437 -1.526)
			(end 0.688 -1.526)
			(stroke
				(width 0.15)
				(type solid)
			)
			(layer "F.Fab")
		)
		(fp_line
			(start -0.437 -1.526)
			(end -0.712 -1.325)
			(stroke
				(width 0.15)
				(type solid)
			)
			(layer "F.Fab")
		)
		(fp_line
			(start -0.712 -1.325)
			(end -0.712 1.523)
			(stroke
				(width 0.15)
				(type solid)
			)
			(layer "F.Fab")
		)
		(fp_line
			(start 0.688 1.519)
			(end 0.688 -1.52)
			(stroke
				(width 0.15)
				(type solid)
			)
			(layer "F.Fab")
		)
		(fp_line
			(start -0.712 1.519)
			(end 0.688 1.519)
			(stroke
				(width 0.15)
				(type solid)
			)
			(layer "F.Fab")
		)
		(pad "1" smd roundrect
			(at -1.1 -0.951 90)
			(size 1 0.6)
			(layers "F.Cu" "F.Mask" "F.Paste")
			(roundrect_rratio 0.15)
			(net 546 "/Com Express 7 MGMT/~{COM7}")
			(pinfunction "G")
			(pintype "bidirectional")
			(teardrops
				(best_length_ratio 0.2)
				(max_length 1)
				(best_width_ratio 0.9)
				(max_width 2)
				(curved_edges yes)
				(filter_ratio 0.9)
				(enabled yes)
				(allow_two_segments yes)
				(prefer_zone_connections yes)
			)
		)
		(pad "2" smd roundrect
			(at -1.1 0.949 90)
			(size 1 0.6)
			(layers "F.Cu" "F.Mask" "F.Paste")
			(roundrect_rratio 0.15)
			(net 1 "GND")
			(pinfunction "S")
			(pintype "bidirectional")
			(teardrops
				(best_length_ratio 0.2)
				(max_length 1)
				(best_width_ratio 0.9)
				(max_width 2)
				(curved_edges yes)
				(filter_ratio 0.9)
				(enabled yes)
				(allow_two_segments yes)
				(prefer_zone_connections yes)
			)
		)
		(pad "3" smd roundrect
			(at 1.1 -0.0005 90)
			(size 1 0.6)
			(layers "F.Cu" "F.Mask" "F.Paste")
			(roundrect_rratio 0.15)
			(net 533 "/Com Express 7 MGMT/PSON")
			(pinfunction "D")
			(pintype "bidirectional")
			(teardrops
				(best_length_ratio 0.2)
				(max_length 1)
				(best_width_ratio 0.9)
				(max_width 2)
				(curved_edges yes)
				(filter_ratio 0.9)
				(enabled yes)
				(allow_two_segments yes)
				(prefer_zone_connections yes)
			)
		)
	)
	(footprint "antmicro-footprints:SOT-23-8"
		(layer "F.Cu")
		(at 305.5 149.11 -90)
		(descr "http://www.ti.com/lit/ds/symlink/ina219.pdf")
		(property "Reference" "U48"
			(at -1.1 1.8 90)
			(layer "F.SilkS")
			(effects
				(font
					(size 0.7 0.7)
					(thickness 0.15)
				)
				(justify right bottom)
			)
		)
		(property "Value" "INA219AIDCNR"
			(at 0 2.8 90)
			(layer "F.Fab")
			(effects
				(font
					(size 0.7 0.7)
					(thickness 0.15)
				)
				(justify right bottom)
			)
		)
		(property "Datasheet" "https://www.ti.com/lit/ds/symlink/ina219.pdf?ts=1713856455637&ref_url=https%253A%252F%252Fwww.mouser.es%252F"
			(at 0 0 270)
			(layer "F.Fab")
			(hide yes)
			(effects
				(font
					(size 1.27 1.27)
					(thickness 0.15)
				)
			)
		)
		(property "Author" "Antmicro"
			(at 156.39 454.61 0)
			(layer "F.Fab")
			(hide yes)
			(effects
				(font
					(size 1 1)
					(thickness 0.15)
				)
			)
		)
		(property "License" "Apache-2.0"
			(at 156.39 454.61 0)
			(layer "F.Fab")
			(hide yes)
			(effects
				(font
					(size 1 1)
					(thickness 0.15)
				)
			)
		)
		(property "MPN" "INA219AIDCNR"
			(at 156.39 454.61 0)
			(layer "F.Fab")
			(hide yes)
			(effects
				(font
					(size 1 1)
					(thickness 0.15)
				)
			)
		)
		(property "Manufacturer" "Texas Instruments"
			(at 156.39 454.61 0)
			(layer "F.Fab")
			(hide yes)
			(effects
				(font
					(size 1 1)
					(thickness 0.15)
				)
			)
		)
		(sheetname "Power")
		(sheetfile "power.kicad_sch")
		(attr smd)
		(fp_line
			(start -0.987 1.6)
			(end -0.987 1.324)
			(stroke
				(width 0.15)
				(type solid)
			)
			(layer "F.SilkS")
		)
		(fp_line
			(start -0.613 1.6)
			(end -0.987 1.6)
			(stroke
				(width 0.15)
				(type solid)
			)
			(layer "F.SilkS")
		)
		(fp_line
			(start 1 1.6)
			(end 0.6 1.6)
			(stroke
				(width 0.15)
				(type solid)
			)
			(layer "F.SilkS")
		)
		(fp_line
			(start 1 1.3)
			(end 1 1.6)
			(stroke
				(width 0.15)
				(type solid)
			)
			(layer "F.SilkS")
		)
		(fp_line
			(start -1 -1.3)
			(end -1 -1.6)
			(stroke
				(width 0.15)
				(type solid)
			)
			(layer "F.SilkS")
		)
		(fp_line
			(start 1 -1.3)
			(end 1 -1.6)
			(stroke
				(width 0.15)
				(type solid)
			)
			(layer "F.SilkS")
		)
		(fp_line
			(start -1 -1.6)
			(end -0.6 -1.6)
			(stroke
				(width 0.15)
				(type solid)
			)
			(layer "F.SilkS")
		)
		(fp_line
			(start 1 -1.6)
			(end 0.625 -1.6)
			(stroke
				(width 0.15)
				(type solid)
			)
			(layer "F.SilkS")
		)
		(fp_circle
			(center -1.3 -1.4)
			(end -1.25 -1.4)
			(stroke
				(width 0.15)
				(type solid)
			)
			(fill yes)
			(layer "F.SilkS")
		)
		(fp_rect
			(start -1.9 -1.75)
			(end 1.898 1.75)
			(stroke
				(width 0.05)
				(type solid)
			)
			(fill no)
			(layer "F.CrtYd")
		)
		(fp_line
			(start -1.4 -1.25)
			(end -1.2 -1.45)
			(stroke
				(width 0.15)
				(type solid)
			)
			(layer "F.Fab")
		)
		(fp_rect
			(start -1.401 -1.45)
			(end 1.398 1.449)
			(stroke
				(width 0.15)
				(type solid)
			)
			(fill no)
			(layer "F.Fab")
		)
		(pad "1" smd roundrect
			(at -1.3 -0.975 180)
			(size 0.45 1.1)
			(layers "F.Cu" "F.Mask" "F.Paste")
			(roundrect_rratio 0.25)
			(net 145 "Net-(D24-C)")
			(pinfunction "IN+")
			(pintype "passive")
			(teardrops
				(best_length_ratio 0.2)
				(max_length 1)
				(best_width_ratio 0.9)
				(max_width 2)
				(curved_edges yes)
				(filter_ratio 0.9)
				(enabled yes)
				(allow_two_segments yes)
				(prefer_zone_connections yes)
			)
		)
		(pad "2" smd roundrect
			(at -1.3 -0.325 180)
			(size 0.45 1.1)
			(layers "F.Cu" "F.Mask" "F.Paste")
			(roundrect_rratio 0.25)
			(net 62 "+12V_AON")
			(pinfunction "IN-")
			(pintype "passive")
			(teardrops
				(best_length_ratio 0.2)
				(max_length 1)
				(best_width_ratio 0.9)
				(max_width 2)
				(curved_edges yes)
				(filter_ratio 0.9)
				(enabled yes)
				(allow_two_segments yes)
				(prefer_zone_connections yes)
			)
		)
		(pad "3" smd roundrect
			(at -1.3 0.325 180)
			(size 0.45 1.1)
			(layers "F.Cu" "F.Mask" "F.Paste")
			(roundrect_rratio 0.25)
			(net 1 "GND")
			(pinfunction "GND")
			(pintype "power_in")
			(teardrops
				(best_length_ratio 0.2)
				(max_length 1)
				(best_width_ratio 0.9)
				(max_width 2)
				(curved_edges yes)
				(filter_ratio 0.9)
				(enabled yes)
				(allow_two_segments yes)
				(prefer_zone_connections yes)
			)
		)
		(pad "4" smd roundrect
			(at -1.3 0.975 180)
			(size 0.45 1.1)
			(layers "F.Cu" "F.Mask" "F.Paste")
			(roundrect_rratio 0.25)
			(net 73 "+3V3_AON")
			(pinfunction "V_{S}")
			(pintype "power_in")
			(teardrops
				(best_length_ratio 0.2)
				(max_length 1)
				(best_width_ratio 0.9)
				(max_width 2)
				(curved_edges yes)
				(filter_ratio 0.9)
				(enabled yes)
				(allow_two_segments yes)
				(prefer_zone_connections yes)
			)
		)
		(pad "5" smd roundrect
			(at 1.3 0.975 180)
			(size 0.45 1.1)
			(layers "F.Cu" "F.Mask" "F.Paste")
			(roundrect_rratio 0.25)
			(net 371 "/Com Express 7 MGMT/I2C.SCL")
			(pinfunction "SCL")
			(pintype "open_collector")
			(teardrops
				(best_length_ratio 0.2)
				(max_length 1)
				(best_width_ratio 0.9)
				(max_width 2)
				(curved_edges yes)
				(filter_ratio 0.9)
				(enabled yes)
				(allow_two_segments yes)
				(prefer_zone_connections yes)
			)
		)
		(pad "6" smd roundrect
			(at 1.3 0.325 180)
			(size 0.45 1.1)
			(layers "F.Cu" "F.Mask" "F.Paste")
			(roundrect_rratio 0.25)
			(net 372 "/Com Express 7 MGMT/I2C.SDA")
			(pinfunction "SDA")
			(pintype "open_collector")
			(teardrops
				(best_length_ratio 0.2)
				(max_length 1)
				(best_width_ratio 0.9)
				(max_width 2)
				(curved_edges yes)
				(filter_ratio 0.9)
				(enabled yes)
				(allow_two_segments yes)
				(prefer_zone_connections yes)
			)
		)
		(pad "7" smd roundrect
			(at 1.3 -0.325 180)
			(size 0.45 1.1)
			(layers "F.Cu" "F.Mask" "F.Paste")
			(roundrect_rratio 0.25)
			(net 1 "GND")
			(pinfunction "A0")
			(pintype "passive")
			(teardrops
				(best_length_ratio 0.2)
				(max_length 1)
				(best_width_ratio 0.9)
				(max_width 2)
				(curved_edges yes)
				(filter_ratio 0.9)
				(enabled yes)
				(allow_two_segments yes)
				(prefer_zone_connections yes)
			)
		)
		(pad "8" smd roundrect
			(at 1.3 -0.975 180)
			(size 0.45 1.1)
			(layers "F.Cu" "F.Mask" "F.Paste")
			(roundrect_rratio 0.25)
			(net 1 "GND")
			(pinfunction "A1")
			(pintype "passive")
			(teardrops
				(best_length_ratio 0.2)
				(max_length 1)
				(best_width_ratio 0.9)
				(max_width 2)
				(curved_edges yes)
				(filter_ratio 0.9)
				(enabled yes)
				(allow_two_segments yes)
				(prefer_zone_connections yes)
			)
		)
	)
	(footprint "antmicro-footprints:C_0201"
		(layer "F.Cu")
		(at 155.572 147.31 90)
		(descr "Capacitor SMD 0201")
		(tags "capacitor SMD 0201")
		(property "Reference" "C153"
			(at -4.125 0.278 90)
			(layer "F.SilkS")
			(effects
				(font
					(size 0.7 0.7)
					(thickness 0.15)
				)
				(justify left bottom)
			)
		)
		(property "Value" "C_100n_0201_25V"
			(at 0 1.4 90)
			(layer "F.Fab")
			(effects
				(font
					(size 0.7 0.7)
					(thickness 0.15)
				)
				(justify left bottom)
			)
		)
		(property "Datasheet" "https://product.tdk.com/en/search/capacitor/ceramic/mlcc/info?part_no=C0603X5R1E104K030BB"
			(at 0 0 90)
			(layer "F.Fab")
			(hide yes)
			(effects
				(font
					(size 1.27 1.27)
					(thickness 0.15)
				)
			)
		)
		(property "Author" "Antmicro"
			(at 302.882 -8.262 0)
			(layer "F.Fab")
			(hide yes)
			(effects
				(font
					(size 1 1)
					(thickness 0.15)
				)
			)
		)
		(property "Dielectric" ""
			(at 302.882 -8.262 0)
			(layer "F.Fab")
			(hide yes)
			(effects
				(font
					(size 1 1)
					(thickness 0.15)
				)
			)
		)
		(property "License" "Apache-2.0"
			(at 302.882 -8.262 0)
			(layer "F.Fab")
			(hide yes)
			(effects
				(font
					(size 1 1)
					(thickness 0.15)
				)
			)
		)
		(property "MPN" "C0603X5R1E104K030BB"
			(at 302.882 -8.262 0)
			(layer "F.Fab")
			(hide yes)
			(effects
				(font
					(size 1 1)
					(thickness 0.15)
				)
			)
		)
		(property "Manufacturer" "TDK"
			(at 302.882 -8.262 0)
			(layer "F.Fab")
			(hide yes)
			(effects
				(font
					(size 1 1)
					(thickness 0.15)
				)
			)
		)
		(property "Public" "False"
			(at 302.882 -8.262 0)
			(layer "F.Fab")
			(hide yes)
			(effects
				(font
					(size 1 1)
					(thickness 0.15)
				)
			)
		)
		(property "Val" "100n"
			(at 302.882 -8.262 0)
			(layer "F.Fab")
			(hide yes)
			(effects
				(font
					(size 1 1)
					(thickness 0.15)
				)
			)
		)
		(property "Voltage" "25V"
			(at 302.882 -8.262 0)
			(layer "F.Fab")
			(hide yes)
			(effects
				(font
					(size 1 1)
					(thickness 0.15)
				)
			)
		)
		(sheetname "KR to SFI #1")
		(sheetfile "kr_sfi.kicad_sch")
		(attr smd)
		(fp_rect
			(start -0.7 -0.35)
			(end 0.7 0.35)
			(stroke
				(width 0.05)
				(type default)
			)
			(fill no)
			(layer "F.CrtYd")
		)
		(fp_rect
			(start 0.3 0.15)
			(end -0.301 -0.149)
			(stroke
				(width 0.15)
				(type solid)
			)
			(fill no)
			(layer "F.Fab")
		)
		(pad "" smd roundrect
			(at -0.349 -0.002 90)
			(size 0.318 0.36)
			(layers "F.Paste")
			(roundrect_rratio 0.25)
			(teardrops
				(best_length_ratio 0.2)
				(max_length 1)
				(best_width_ratio 0.9)
				(max_width 2)
				(curved_edges yes)
				(filter_ratio 0.9)
				(enabled yes)
				(allow_two_segments yes)
				(prefer_zone_connections yes)
			)
		)
		(pad "" smd roundrect
			(at 0.341 -0.002 90)
			(size 0.318 0.36)
			(layers "F.Paste")
			(roundrect_rratio 0.25)
			(teardrops
				(best_length_ratio 0.2)
				(max_length 1)
				(best_width_ratio 0.9)
				(max_width 2)
				(curved_edges yes)
				(filter_ratio 0.9)
				(enabled yes)
				(allow_two_segments yes)
				(prefer_zone_connections yes)
			)
		)
		(pad "1" smd roundrect
			(at -0.321 -0.002 90)
			(size 0.46 0.4)
			(layers "F.Cu" "F.Mask")
			(roundrect_rratio 0.25)
			(net 111 "/2xSFP+/10GKR_SFP0.TX+")
			(pintype "passive")
			(teardrops
				(best_length_ratio 0.2)
				(max_length 1)
				(best_width_ratio 0.9)
				(max_width 2)
				(curved_edges yes)
				(filter_ratio 0.9)
				(enabled yes)
				(allow_two_segments yes)
				(prefer_zone_connections yes)
			)
		)
		(pad "2" smd roundrect
			(at 0.32 -0.002 90)
			(size 0.46 0.4)
			(layers "F.Cu" "F.Mask")
			(roundrect_rratio 0.25)
			(net 112 "/2xSFP+/KR to SFI #1/KR_C.TX+")
			(pintype "passive")
			(teardrops
				(best_length_ratio 0.2)
				(max_length 1)
				(best_width_ratio 0.9)
				(max_width 2)
				(curved_edges yes)
				(filter_ratio 0.9)
				(enabled yes)
				(allow_two_segments yes)
				(prefer_zone_connections yes)
			)
		)
	)
)
